(kicad_pcb
	(version 20260206)
	(generator "pcbnew")
	(generator_version "10.0")
	(general
		(thickness 1.6)
		(legacy_teardrops no)
	)
	(paper "A4")
	(title_block
		(title "panther-plus-userver — 13130-1b_20150205.brd")
		(comment 1 "Honey Badger (Wiwynn) / footprints 1297-1304 of 1509")
	)
	(layers
		(0 "F.Cu" signal "TOP")
		(4 "In1.Cu" signal "L2")
		(6 "In2.Cu" signal "L3")
		(8 "In3.Cu" signal "L4")
		(10 "In4.Cu" signal "L5")
		(12 "In5.Cu" signal "L6")
		(14 "In6.Cu" signal "L7")
		(16 "In7.Cu" signal "L8")
		(18 "In8.Cu" signal "L9")
		(20 "In9.Cu" signal "L10")
		(22 "In10.Cu" signal "L11")
		(2 "B.Cu" signal "BOTTOM")
		(9 "F.Adhes" user "F.Adhesive")
		(11 "B.Adhes" user "B.Adhesive")
		(13 "F.Paste" user "Package Geometry/Pastemask Top")
		(15 "B.Paste" user "Package Geometry/Pastemask Bottom")
		(5 "F.SilkS" user "Ref Des/Silkscreen Top")
		(7 "B.SilkS" user "Ref Des/Silkscreen Bottom")
		(1 "F.Mask" user "Board Geometry/Soldermask Top")
		(3 "B.Mask" user "Board Geometry/Soldermask Bottom")
		(17 "Dwgs.User" user "User.Drawings")
		(19 "Cmts.User" user "User.Comments")
		(21 "Eco1.User" user "User.Eco1")
		(23 "Eco2.User" user "User.Eco2")
		(25 "Edge.Cuts" user "Board Geometry/Outline")
		(27 "Margin" user)
		(31 "F.CrtYd" user "Package Geometry/Place Bound Top")
		(29 "B.CrtYd" user "Package Geometry/Place Bound Bottom")
		(35 "F.Fab" user "Ref Des/Assembly Top")
		(33 "B.Fab" user "Ref Des/Assembly Bottom")
	)
	(footprint ""
		(layer "B.Cu")
		(at 92.226384 -50.689002 -90)
		(property "Reference" "R282"
			(at 0 0 90)
			(layer "B.SilkS")
			(hide yes)
			(effects
				(font
					(size 1.27 1.27)
				)
				(justify mirror)
			)
		)
		(property "Value" "402R2F-GP"
			(at -0.064008 -3.993896 270)
			(unlocked yes)
			(layer "B.Fab")
			(hide yes)
			(effects
				(font
					(size 1.016 1.016)
					(thickness 0.1524)
				)
				(justify mirror)
			)
		)
		(property "Device Type" "R402H16"
			(at -0.064008 -5.517896 270)
			(unlocked yes)
			(layer "B.Fab")
			(hide yes)
			(effects
				(font
					(size 1.016 1.016)
					(thickness 0.1524)
				)
				(justify mirror)
			)
		)
		(duplicate_pad_numbers_are_jumpers no)
		(fp_rect
			(start 0.381 0.8382)
			(end -0.381 -0.8382)
			(stroke
				(width 0)
				(type default)
			)
			(fill no)
			(layer "B.CrtYd")
		)
		(fp_rect
			(start 0.381 0.8382)
			(end -0.381 -0.8382)
			(stroke
				(width 0)
				(type default)
			)
			(fill no)
			(layer "B.Fab")
		)
		(pad "1" smd custom
			(at 0 -0.4318 90)
			(size 0.127 0.127)
			(layers "B.Cu" "B.Mask" "B.Paste")
			(net "PCIE_OBS_P")
			(options
				(clearance outline)
				(anchor circle)
			)
			(primitives
				(gr_poly
					(pts
						(arc
							(start -0.2032 0.2794)
							(mid -0.239121 0.264521)
							(end -0.254 0.2286)
						)
						(arc
							(start -0.254 -0.2286)
							(mid -0.239121 -0.264521)
							(end -0.2032 -0.2794)
						)
						(arc
							(start 0.2032 -0.2794)
							(mid 0.239121 -0.264521)
							(end 0.254 -0.2286)
						)
						(arc
							(start 0.254 0.2286)
							(mid 0.239121 0.264521)
							(end 0.2032 0.2794)
						)
					)
					(width 0)
					(fill yes)
				)
			)
		)
		(pad "2" smd custom
			(at 0 0.4318 90)
			(size 0.127 0.127)
			(layers "B.Cu" "B.Mask" "B.Paste")
			(net "PCIE_OBS_N")
			(options
				(clearance outline)
				(anchor circle)
			)
			(primitives
				(gr_poly
					(pts
						(arc
							(start -0.2032 0.2794)
							(mid -0.239121 0.264521)
							(end -0.254 0.2286)
						)
						(arc
							(start -0.254 -0.2286)
							(mid -0.239121 -0.264521)
							(end -0.2032 -0.2794)
						)
						(arc
							(start 0.2032 -0.2794)
							(mid 0.239121 -0.264521)
							(end 0.254 -0.2286)
						)
						(arc
							(start 0.254 0.2286)
							(mid 0.239121 0.264521)
							(end 0.2032 0.2794)
						)
					)
					(width 0)
					(fill yes)
				)
			)
		)
	)
	(footprint ""
		(layer "B.Cu")
		(at 197.231 -67.564 90)
		(property "Reference" "R410"
			(at 0 0 90)
			(layer "B.SilkS")
			(hide yes)
			(effects
				(font
					(size 1.27 1.27)
				)
				(justify mirror)
			)
		)
		(property "Value" "10KR2F-2-GP"
			(at -1.7907 -1.1176 90)
			(unlocked yes)
			(layer "B.Fab")
			(hide yes)
			(effects
				(font
					(size 1.016 1.016)
					(thickness 0.1524)
				)
				(justify mirror)
			)
		)
		(property "Device Type" "R402H16"
			(at -1.7907 -2.6416 90)
			(unlocked yes)
			(layer "B.Fab")
			(hide yes)
			(effects
				(font
					(size 1.016 1.016)
					(thickness 0.1524)
				)
				(justify mirror)
			)
		)
		(duplicate_pad_numbers_are_jumpers no)
		(fp_rect
			(start 0.381 0.8382)
			(end -0.381 -0.8382)
			(stroke
				(width 0)
				(type default)
			)
			(fill no)
			(layer "B.CrtYd")
		)
		(fp_rect
			(start 0.381 0.8382)
			(end -0.381 -0.8382)
			(stroke
				(width 0)
				(type default)
			)
			(fill no)
			(layer "B.Fab")
		)
		(pad "1" smd custom
			(at 0 -0.4318 270)
			(size 0.127 0.127)
			(layers "B.Cu" "B.Mask" "B.Paste")
			(net "P3V3")
			(options
				(clearance outline)
				(anchor circle)
			)
			(primitives
				(gr_poly
					(pts
						(arc
							(start -0.2032 0.2794)
							(mid -0.239121 0.264521)
							(end -0.254 0.2286)
						)
						(arc
							(start -0.254 -0.2286)
							(mid -0.239121 -0.264521)
							(end -0.2032 -0.2794)
						)
						(arc
							(start 0.2032 -0.2794)
							(mid 0.239121 -0.264521)
							(end 0.254 -0.2286)
						)
						(arc
							(start 0.254 0.2286)
							(mid 0.239121 0.264521)
							(end 0.2032 0.2794)
						)
					)
					(width 0)
					(fill yes)
				)
			)
		)
		(pad "2" smd custom
			(at 0 0.4318 270)
			(size 0.127 0.127)
			(layers "B.Cu" "B.Mask" "B.Paste")
			(net "PWR_STATUS_LED_EN")
			(options
				(clearance outline)
				(anchor circle)
			)
			(primitives
				(gr_poly
					(pts
						(arc
							(start -0.2032 0.2794)
							(mid -0.239121 0.264521)
							(end -0.254 0.2286)
						)
						(arc
							(start -0.254 -0.2286)
							(mid -0.239121 -0.264521)
							(end -0.2032 -0.2794)
						)
						(arc
							(start 0.2032 -0.2794)
							(mid 0.239121 -0.264521)
							(end 0.254 -0.2286)
						)
						(arc
							(start 0.254 0.2286)
							(mid 0.239121 0.264521)
							(end 0.2032 0.2794)
						)
					)
					(width 0)
					(fill yes)
				)
			)
		)
	)
	(footprint ""
		(layer "B.Cu")
		(at 18.796 -24.003 -90)
		(property "Reference" "PR84"
			(at 0 0 90)
			(layer "B.SilkS")
			(hide yes)
			(effects
				(font
					(size 1.27 1.27)
				)
				(justify mirror)
			)
		)
		(property "Value" "0R2J-2-GP"
			(at -1.7907 -1.1176 270)
			(unlocked yes)
			(layer "B.Fab")
			(hide yes)
			(effects
				(font
					(size 1.016 1.016)
					(thickness 0.1524)
				)
				(justify mirror)
			)
		)
		(property "Device Type" "R402H16"
			(at -1.7907 -2.6416 270)
			(unlocked yes)
			(layer "B.Fab")
			(hide yes)
			(effects
				(font
					(size 1.016 1.016)
					(thickness 0.1524)
				)
				(justify mirror)
			)
		)
		(duplicate_pad_numbers_are_jumpers no)
		(fp_rect
			(start 0.381 0.8382)
			(end -0.381 -0.8382)
			(stroke
				(width 0)
				(type default)
			)
			(fill no)
			(layer "B.CrtYd")
		)
		(fp_rect
			(start 0.381 0.8382)
			(end -0.381 -0.8382)
			(stroke
				(width 0)
				(type default)
			)
			(fill no)
			(layer "B.Fab")
		)
		(pad "1" smd custom
			(at 0 -0.4318 90)
			(size 0.127 0.127)
			(layers "B.Cu" "B.Mask" "B.Paste")
			(net "AGND_P1V0")
			(options
				(clearance outline)
				(anchor circle)
			)
			(primitives
				(gr_poly
					(pts
						(arc
							(start -0.2032 0.2794)
							(mid -0.239121 0.264521)
							(end -0.254 0.2286)
						)
						(arc
							(start -0.254 -0.2286)
							(mid -0.239121 -0.264521)
							(end -0.2032 -0.2794)
						)
						(arc
							(start 0.2032 -0.2794)
							(mid 0.239121 -0.264521)
							(end 0.254 -0.2286)
						)
						(arc
							(start 0.254 0.2286)
							(mid 0.239121 0.264521)
							(end 0.2032 0.2794)
						)
					)
					(width 0)
					(fill yes)
				)
			)
		)
		(pad "2" smd custom
			(at 0 0.4318 90)
			(size 0.127 0.127)
			(layers "B.Cu" "B.Mask" "B.Paste")
			(net "P1V0_ROVP")
			(options
				(clearance outline)
				(anchor circle)
			)
			(primitives
				(gr_poly
					(pts
						(arc
							(start -0.2032 0.2794)
							(mid -0.239121 0.264521)
							(end -0.254 0.2286)
						)
						(arc
							(start -0.254 -0.2286)
							(mid -0.239121 -0.264521)
							(end -0.2032 -0.2794)
						)
						(arc
							(start 0.2032 -0.2794)
							(mid 0.239121 -0.264521)
							(end 0.254 -0.2286)
						)
						(arc
							(start 0.254 0.2286)
							(mid 0.239121 0.264521)
							(end 0.2032 0.2794)
						)
					)
					(width 0)
					(fill yes)
				)
			)
		)
	)
	(footprint ""
		(layer "B.Cu")
		(at 19.177 -64.77)
		(property "Reference" "PR22"
			(at 0 0 0)
			(layer "B.SilkS")
			(hide yes)
			(effects
				(font
					(size 1.27 1.27)
				)
				(justify mirror)
			)
		)
		(property "Value" "0R2J-2-GP"
			(at -1.7907 -1.1176 0)
			(unlocked yes)
			(layer "B.Fab")
			(hide yes)
			(effects
				(font
					(size 1.016 1.016)
					(thickness 0.1524)
				)
				(justify mirror)
			)
		)
		(property "Device Type" "R402H16"
			(at -1.7907 -2.6416 0)
			(unlocked yes)
			(layer "B.Fab")
			(hide yes)
			(effects
				(font
					(size 1.016 1.016)
					(thickness 0.1524)
				)
				(justify mirror)
			)
		)
		(duplicate_pad_numbers_are_jumpers no)
		(fp_rect
			(start 0.381 0.8382)
			(end -0.381 -0.8382)
			(stroke
				(width 0)
				(type default)
			)
			(fill no)
			(layer "B.CrtYd")
		)
		(fp_rect
			(start 0.381 0.8382)
			(end -0.381 -0.8382)
			(stroke
				(width 0)
				(type default)
			)
			(fill no)
			(layer "B.Fab")
		)
		(pad "1" smd custom
			(at 0 -0.4318 180)
			(size 0.127 0.127)
			(layers "B.Cu" "B.Mask" "B.Paste")
			(net "PVNN")
			(options
				(clearance outline)
				(anchor circle)
			)
			(primitives
				(gr_poly
					(pts
						(arc
							(start -0.2032 0.2794)
							(mid -0.239121 0.264521)
							(end -0.254 0.2286)
						)
						(arc
							(start -0.254 -0.2286)
							(mid -0.239121 -0.264521)
							(end -0.2032 -0.2794)
						)
						(arc
							(start 0.2032 -0.2794)
							(mid 0.239121 -0.264521)
							(end 0.254 -0.2286)
						)
						(arc
							(start 0.254 0.2286)
							(mid 0.239121 0.264521)
							(end 0.2032 0.2794)
						)
					)
					(width 0)
					(fill yes)
				)
			)
		)
		(pad "2" smd custom
			(at 0 0.4318 180)
			(size 0.127 0.127)
			(layers "B.Cu" "B.Mask" "B.Paste")
			(net "VR_PVNN_VSEN")
			(options
				(clearance outline)
				(anchor circle)
			)
			(primitives
				(gr_poly
					(pts
						(arc
							(start -0.2032 0.2794)
							(mid -0.239121 0.264521)
							(end -0.254 0.2286)
						)
						(arc
							(start -0.254 -0.2286)
							(mid -0.239121 -0.264521)
							(end -0.2032 -0.2794)
						)
						(arc
							(start 0.2032 -0.2794)
							(mid 0.239121 -0.264521)
							(end 0.254 -0.2286)
						)
						(arc
							(start 0.254 0.2286)
							(mid 0.239121 0.264521)
							(end 0.2032 0.2794)
						)
					)
					(width 0)
					(fill yes)
				)
			)
		)
	)
	(footprint ""
		(layer "B.Cu")
		(at 37.46881 -12.7)
		(property "Reference" "C267"
			(at 0 0 0)
			(layer "B.SilkS")
			(hide yes)
			(effects
				(font
					(size 1.27 1.27)
				)
				(justify mirror)
			)
		)
		(property "Value" "SCD1U16V2KX-3GP"
			(at -1.1811 -2.7051 0)
			(unlocked yes)
			(layer "B.Fab")
			(hide yes)
			(effects
				(font
					(size 1.016 1.016)
					(thickness 0.1524)
				)
				(justify mirror)
			)
		)
		(property "Device Type" "C402H22"
			(at -1.1811 -4.2291 0)
			(unlocked yes)
			(layer "B.Fab")
			(hide yes)
			(effects
				(font
					(size 1.016 1.016)
					(thickness 0.1524)
				)
				(justify mirror)
			)
		)
		(duplicate_pad_numbers_are_jumpers no)
		(fp_rect
			(start 0.381 0.7366)
			(end -0.381 -0.7366)
			(stroke
				(width 0)
				(type default)
			)
			(fill no)
			(layer "B.CrtYd")
		)
		(fp_rect
			(start 0.381 0.7366)
			(end -0.381 -0.7366)
			(stroke
				(width 0)
				(type default)
			)
			(fill no)
			(layer "B.Fab")
		)
		(pad "1" smd custom
			(at 0 -0.4572 180)
			(size 0.1143 0.1143)
			(layers "B.Cu" "B.Mask" "B.Paste")
			(net "P2E_CPU_SAS_C_TX_DN6")
			(options
				(clearance outline)
				(anchor circle)
			)
			(primitives
				(gr_poly
					(pts
						(arc
							(start -0.254 0.1778)
							(mid -0.239121 0.213721)
							(end -0.2032 0.2286)
						)
						(arc
							(start 0.2032 0.2286)
							(mid 0.239121 0.213721)
							(end 0.254 0.1778)
						)
						(arc
							(start 0.254 -0.1778)
							(mid 0.239121 -0.213721)
							(end 0.2032 -0.2286)
						)
						(arc
							(start -0.2032 -0.2286)
							(mid -0.239121 -0.213721)
							(end -0.254 -0.1778)
						)
					)
					(width 0)
					(fill yes)
				)
			)
		)
		(pad "2" smd custom
			(at 0 0.4572 180)
			(size 0.1143 0.1143)
			(layers "B.Cu" "B.Mask" "B.Paste")
			(net "P2E_CPU_SAS_TX_DN6")
			(options
				(clearance outline)
				(anchor circle)
			)
			(primitives
				(gr_poly
					(pts
						(arc
							(start -0.254 0.1778)
							(mid -0.239121 0.213721)
							(end -0.2032 0.2286)
						)
						(arc
							(start 0.2032 0.2286)
							(mid 0.239121 0.213721)
							(end 0.254 0.1778)
						)
						(arc
							(start 0.254 -0.1778)
							(mid 0.239121 -0.213721)
							(end 0.2032 -0.2286)
						)
						(arc
							(start -0.2032 -0.2286)
							(mid -0.239121 -0.213721)
							(end -0.254 -0.1778)
						)
					)
					(width 0)
					(fill yes)
				)
			)
		)
	)
	(footprint ""
		(layer "B.Cu")
		(at 6.096 -33.401 90)
		(property "Reference" "PR207"
			(at 0 0 90)
			(layer "B.SilkS")
			(hide yes)
			(effects
				(font
					(size 1.27 1.27)
				)
				(justify mirror)
			)
		)
		(property "Value" "10KR2F-2-GP"
			(at -1.7907 -1.1176 90)
			(unlocked yes)
			(layer "B.Fab")
			(hide yes)
			(effects
				(font
					(size 1.016 1.016)
					(thickness 0.1524)
				)
				(justify mirror)
			)
		)
		(property "Device Type" "R402H16"
			(at -1.7907 -2.6416 90)
			(unlocked yes)
			(layer "B.Fab")
			(hide yes)
			(effects
				(font
					(size 1.016 1.016)
					(thickness 0.1524)
				)
				(justify mirror)
			)
		)
		(duplicate_pad_numbers_are_jumpers no)
		(fp_rect
			(start 0.381 0.8382)
			(end -0.381 -0.8382)
			(stroke
				(width 0)
				(type default)
			)
			(fill no)
			(layer "B.CrtYd")
		)
		(fp_rect
			(start 0.381 0.8382)
			(end -0.381 -0.8382)
			(stroke
				(width 0)
				(type default)
			)
			(fill no)
			(layer "B.Fab")
		)
		(pad "1" smd custom
			(at 0 -0.4318 270)
			(size 0.127 0.127)
			(layers "B.Cu" "B.Mask" "B.Paste")
			(net "P3V3_STBY_PG")
			(options
				(clearance outline)
				(anchor circle)
			)
			(primitives
				(gr_poly
					(pts
						(arc
							(start -0.2032 0.2794)
							(mid -0.239121 0.264521)
							(end -0.254 0.2286)
						)
						(arc
							(start -0.254 -0.2286)
							(mid -0.239121 -0.264521)
							(end -0.2032 -0.2794)
						)
						(arc
							(start 0.2032 -0.2794)
							(mid 0.239121 -0.264521)
							(end 0.254 -0.2286)
						)
						(arc
							(start 0.254 0.2286)
							(mid 0.239121 0.264521)
							(end 0.2032 0.2794)
						)
					)
					(width 0)
					(fill yes)
				)
			)
		)
		(pad "2" smd custom
			(at 0 0.4318 270)
			(size 0.127 0.127)
			(layers "B.Cu" "B.Mask" "B.Paste")
			(net "P3V3_STBY_VREG")
			(options
				(clearance outline)
				(anchor circle)
			)
			(primitives
				(gr_poly
					(pts
						(arc
							(start -0.2032 0.2794)
							(mid -0.239121 0.264521)
							(end -0.254 0.2286)
						)
						(arc
							(start -0.254 -0.2286)
							(mid -0.239121 -0.264521)
							(end -0.2032 -0.2794)
						)
						(arc
							(start 0.2032 -0.2794)
							(mid 0.239121 -0.264521)
							(end 0.254 -0.2286)
						)
						(arc
							(start 0.254 0.2286)
							(mid 0.239121 0.264521)
							(end 0.2032 0.2794)
						)
					)
					(width 0)
					(fill yes)
				)
			)
		)
	)
	(footprint ""
		(layer "B.Cu")
		(at 159.512 -59.309)
		(property "Reference" "C108"
			(at 0 0 0)
			(layer "B.SilkS")
			(hide yes)
			(effects
				(font
					(size 1.27 1.27)
				)
				(justify mirror)
			)
		)
		(property "Value" "SC10U6D3V3MX-GP"
			(at 0.0254 -2.0193 0)
			(unlocked yes)
			(layer "B.Fab")
			(hide yes)
			(effects
				(font
					(size 1.016 1.016)
					(thickness 0.1524)
				)
				(justify mirror)
			)
		)
		(property "Device Type" "C603H38"
			(at 0.0254 -3.5433 0)
			(unlocked yes)
			(layer "B.Fab")
			(hide yes)
			(effects
				(font
					(size 1.016 1.016)
					(thickness 0.1524)
				)
				(justify mirror)
			)
		)
		(duplicate_pad_numbers_are_jumpers no)
		(fp_line
			(start 0.4064 0)
			(end -0.4064 0)
			(stroke
				(width 0.2286)
				(type default)
			)
			(layer "B.SilkS")
		)
		(fp_rect
			(start 0.635 1.1811)
			(end -0.635 -1.1811)
			(stroke
				(width 0)
				(type default)
			)
			(fill no)
			(layer "B.CrtYd")
		)
		(fp_rect
			(start 0.635 1.1811)
			(end -0.635 -1.1811)
			(stroke
				(width 0)
				(type default)
			)
			(fill no)
			(layer "B.Fab")
		)
		(pad "1" smd custom
			(at 0 -0.6604 180)
			(size 0.19685 0.19685)
			(layers "B.Cu" "B.Mask" "B.Paste")
			(net "PV_VDDR")
			(options
				(clearance outline)
				(anchor circle)
			)
			(primitives
				(gr_poly
					(pts
						(arc
							(start 0.508 0.2921)
							(mid 0.478242 0.363942)
							(end 0.4064 0.3937)
						)
						(arc
							(start -0.4064 0.3937)
							(mid -0.478242 0.363942)
							(end -0.508 0.2921)
						)
						(arc
							(start -0.508 -0.2921)
							(mid -0.478242 -0.363942)
							(end -0.4064 -0.3937)
						)
						(arc
							(start 0.4064 -0.3937)
							(mid 0.478242 -0.363942)
							(end 0.508 -0.2921)
						)
					)
					(width 0)
					(fill yes)
				)
			)
		)
		(pad "2" smd custom
			(at 0 0.6604 180)
			(size 0.19685 0.19685)
			(layers "B.Cu" "B.Mask" "B.Paste")
			(net "GND")
			(options
				(clearance outline)
				(anchor circle)
			)
			(primitives
				(gr_poly
					(pts
						(arc
							(start 0.508 0.2921)
							(mid 0.478242 0.363942)
							(end 0.4064 0.3937)
						)
						(arc
							(start -0.4064 0.3937)
							(mid -0.478242 0.363942)
							(end -0.508 0.2921)
						)
						(arc
							(start -0.508 -0.2921)
							(mid -0.478242 -0.363942)
							(end -0.4064 -0.3937)
						)
						(arc
							(start 0.4064 -0.3937)
							(mid 0.478242 -0.363942)
							(end 0.508 -0.2921)
						)
					)
					(width 0)
					(fill yes)
				)
			)
		)
	)
	(footprint ""
		(layer "B.Cu")
		(at 187.0456 -33.2486 90)
		(property "Reference" "PC99"
			(at 0 0 90)
			(layer "B.SilkS")
			(hide yes)
			(effects
				(font
					(size 1.27 1.27)
				)
				(justify mirror)
			)
		)
		(property "Value" "SC1KP50V2KX-1GP"
			(at -1.8923 -1.2065 90)
			(unlocked yes)
			(layer "B.Fab")
			(hide yes)
			(effects
				(font
					(size 1.016 1.016)
					(thickness 0.1524)
				)
				(justify mirror)
			)
		)
		(property "Device Type" "C402H22"
			(at -1.8923 -2.7305 90)
			(unlocked yes)
			(layer "B.Fab")
			(hide yes)
			(effects
				(font
					(size 1.016 1.016)
					(thickness 0.1524)
				)
				(justify mirror)
			)
		)
		(duplicate_pad_numbers_are_jumpers no)
		(fp_rect
			(start 0.381 0.7366)
			(end -0.381 -0.7366)
			(stroke
				(width 0)
				(type default)
			)
			(fill no)
			(layer "B.CrtYd")
		)
		(fp_rect
			(start 0.381 0.7366)
			(end -0.381 -0.7366)
			(stroke
				(width 0)
				(type default)
			)
			(fill no)
			(layer "B.Fab")
		)
		(pad "1" smd custom
			(at 0 -0.4572 270)
			(size 0.1143 0.1143)
			(layers "B.Cu" "B.Mask" "B.Paste")
			(net "VR_PVDDR_A_NTC")
			(options
				(clearance outline)
				(anchor circle)
			)
			(primitives
				(gr_poly
					(pts
						(arc
							(start -0.254 0.1778)
							(mid -0.239121 0.213721)
							(end -0.2032 0.2286)
						)
						(arc
							(start 0.2032 0.2286)
							(mid 0.239121 0.213721)
							(end 0.254 0.1778)
						)
						(arc
							(start 0.254 -0.1778)
							(mid 0.239121 -0.213721)
							(end 0.2032 -0.2286)
						)
						(arc
							(start -0.2032 -0.2286)
							(mid -0.239121 -0.213721)
							(end -0.254 -0.1778)
						)
					)
					(width 0)
					(fill yes)
				)
			)
		)
		(pad "2" smd custom
			(at 0 0.4572 270)
			(size 0.1143 0.1143)
			(layers "B.Cu" "B.Mask" "B.Paste")
			(net "GND")
			(options
				(clearance outline)
				(anchor circle)
			)
			(primitives
				(gr_poly
					(pts
						(arc
							(start -0.254 0.1778)
							(mid -0.239121 0.213721)
							(end -0.2032 0.2286)
						)
						(arc
							(start 0.2032 0.2286)
							(mid 0.239121 0.213721)
							(end 0.254 0.1778)
						)
						(arc
							(start 0.254 -0.1778)
							(mid 0.239121 -0.213721)
							(end 0.2032 -0.2286)
						)
						(arc
							(start -0.2032 -0.2286)
							(mid -0.239121 -0.213721)
							(end -0.254 -0.1778)
						)
					)
					(width 0)
					(fill yes)
				)
			)
		)
	)
)
